(kicad_pcb
	(version 20241229)
	(generator "pcbnew")
	(generator_version "9.0")
	(general
		(thickness 1.6296)
		(legacy_teardrops no)
	)
	(paper "A3")
	(title_block
		(title "Thunderbolt to 10GbE adapter")
		(date "2026-04-21")
		(rev "1.1.0")
		(company "Antmicro Ltd")
		(comment 1 "www.antmicro.com")
		(comment 9 "footprint 4 of 703 (U4), pads 163-245 of 337")
	)
	(layers
		(0 "F.Cu" signal)
		(4 "In1.Cu" signal)
		(6 "In2.Cu" signal)
		(8 "In3.Cu" signal)
		(10 "In4.Cu" signal)
		(12 "In5.Cu" signal)
		(14 "In6.Cu" signal)
		(2 "B.Cu" signal)
		(9 "F.Adhes" user "F.Adhesive")
		(11 "B.Adhes" user "B.Adhesive")
		(13 "F.Paste" user)
		(15 "B.Paste" user)
		(5 "F.SilkS" user "F.Silkscreen")
		(7 "B.SilkS" user "B.Silkscreen")
		(1 "F.Mask" user)
		(3 "B.Mask" user)
		(17 "Dwgs.User" user "User.Drawings")
		(19 "Cmts.User" user "User.Comments")
		(21 "Eco1.User" user "User.Eco1")
		(23 "Eco2.User" user "User.Eco2")
		(25 "Edge.Cuts" user)
		(27 "Margin" user)
		(31 "F.CrtYd" user "F.Courtyard")
		(29 "B.CrtYd" user "B.Courtyard")
		(35 "F.Fab" user)
		(33 "B.Fab" user)
	)
	(footprint "antmicro-footprints:JHL6340SLLSQ"
		(layer "F.Cu")
		(at 128.5 123.95 180)
		(property "Reference" "U4"
			(at 4.9 6.15 0)
			(unlocked yes)
			(layer "F.SilkS")
			(effects
				(font
					(size 0.7 0.7)
					(thickness 0.15)
				)
			)
		)
		(property "Value" "JHL6340SLLSQ"
			(at 0 6.4 180)
			(unlocked yes)
			(layer "F.Fab")
			(effects
				(font
					(size 0.7 0.7)
					(thickness 0.15)
				)
			)
		)
		(property "Datasheet" "https://www.thunderbolttechnology.net/sites/default/files/18-241_ThunderboltController_Brief_HI.pdf"
			(at 0 0 180)
			(layer "F.Fab")
			(hide yes)
			(effects
				(font
					(size 1.27 1.27)
					(thickness 0.15)
				)
			)
		)
		(property "Description" "Thunderbolt™ 3 Controller, I/O"
			(at 0 0 180)
			(layer "F.Fab")
			(hide yes)
			(effects
				(font
					(size 1.27 1.27)
					(thickness 0.15)
				)
			)
		)
		(property "Manufacturer" "Intel"
			(at 0 0 180)
			(unlocked yes)
			(layer "F.Fab")
			(hide yes)
			(effects
				(font
					(size 1 1)
					(thickness 0.15)
				)
			)
		)
		(property "MPN" "JHL6340SLLSQ"
			(at 0 0 180)
			(unlocked yes)
			(layer "F.Fab")
			(hide yes)
			(effects
				(font
					(size 1 1)
					(thickness 0.15)
				)
			)
		)
		(property "Author" "Antmicro"
			(at 0 0 180)
			(unlocked yes)
			(layer "F.Fab")
			(hide yes)
			(effects
				(font
					(size 1 1)
					(thickness 0.15)
				)
			)
		)
		(property "License" "Apache-2.0"
			(at 0 0 180)
			(unlocked yes)
			(layer "F.Fab")
			(hide yes)
			(effects
				(font
					(size 1 1)
					(thickness 0.15)
				)
			)
		)
		(sheetname "/TB Controller/")
		(sheetfile "tb.kicad_sch")
		(attr smd)
		(pad "H11" smd circle
			(at -0.65 -1.95 180)
			(size 0.254 0.254)
			(layers "F.Cu" "F.Mask" "F.Paste")
			(net 180 "Net-(U4A-VCC0P9_LVR_SENSE)")
			(pinfunction "VCC0P9_LVR_SENSE")
			(pintype "power_in")
		)
		(pad "H12" smd circle
			(at 0 -1.95 180)
			(size 0.254 0.254)
			(layers "F.Cu" "F.Mask" "F.Paste")
			(net 23 "GND")
			(pinfunction "VSS_ANA")
			(pintype "passive")
		)
		(pad "H13" smd circle
			(at 0.65 -1.95 180)
			(size 0.254 0.254)
			(layers "F.Cu" "F.Mask" "F.Paste")
			(net 23 "GND")
			(pinfunction "VSS_ANA")
			(pintype "passive")
		)
		(pad "H15" smd circle
			(at 1.3 -1.95 180)
			(size 0.254 0.254)
			(layers "F.Cu" "F.Mask" "F.Paste")
			(net 23 "GND")
			(pinfunction "VSS_ANA")
			(pintype "passive")
		)
		(pad "H16" smd circle
			(at 1.95 -1.95 180)
			(size 0.254 0.254)
			(layers "F.Cu" "F.Mask" "F.Paste")
			(net 23 "GND")
			(pinfunction "VSS_ANA")
			(pintype "passive")
		)
		(pad "H18" smd circle
			(at 2.6 -1.95 180)
			(size 0.254 0.254)
			(layers "F.Cu" "F.Mask" "F.Paste")
			(net 180 "Net-(U4A-VCC0P9_LVR_SENSE)")
			(pinfunction "VCC0P9_LVR")
			(pintype "passive")
		)
		(pad "H19" smd circle
			(at 3.25 -1.95 180)
			(size 0.254 0.254)
			(layers "F.Cu" "F.Mask" "F.Paste")
			(net 228 "Net-(U4E-PA_USB2_RBIAS)")
			(pinfunction "PA_USB2_RBIAS")
			(pintype "passive")
		)
		(pad "H20" smd circle
			(at 3.9 -1.95 180)
			(size 0.254 0.254)
			(layers "F.Cu" "F.Mask" "F.Paste")
			(net 23 "GND")
			(pinfunction "VSS_ANA")
			(pintype "passive")
		)
		(pad "H22" smd circle
			(at 4.6 -1.84 180)
			(size 0.254 0.254)
			(layers "F.Cu" "F.Mask" "F.Paste")
			(net 595 "/TB Controller/PCIex4.TX3-")
			(pinfunction "PCIE_RX3_N")
			(pintype "input")
		)
		(pad "H23" smd oval
			(at 5.06 -1.84 270)
			(size 0.1578 0.3302)
			(layers "F.Cu" "F.Mask" "F.Paste")
			(net 601 "/TB Controller/PCIex4.TX3+")
			(pinfunction "PCIE_RX3_P")
			(pintype "input")
		)
		(pad "J1" smd oval
			(at -5.06 -1.38 270)
			(size 0.1578 0.3302)
			(layers "F.Cu" "F.Mask" "F.Paste")
			(net 273 "unconnected-(U4C-DPSRC_ML3_N-PadJ1)")
			(pinfunction "DPSRC_ML3_N")
			(pintype "output+no_connect")
		)
		(pad "J2" smd circle
			(at -4.6 -1.38 180)
			(size 0.254 0.254)
			(layers "F.Cu" "F.Mask" "F.Paste")
			(net 274 "unconnected-(U4C-DPSRC_ML3_P-PadJ2)")
			(pinfunction "DPSRC_ML3_P")
			(pintype "output+no_connect")
		)
		(pad "J4" smd circle
			(at -3.9 -1.3 180)
			(size 0.254 0.254)
			(layers "F.Cu" "F.Mask" "F.Paste")
			(net 372 "/PD and TB DC-DC/I2C1.IRQ")
			(pinfunction "POC_GPIO_0")
			(pintype "bidirectional")
		)
		(pad "J5" smd circle
			(at -3.25 -1.3 180)
			(size 0.254 0.254)
			(layers "F.Cu" "F.Mask" "F.Paste")
			(net 23 "GND")
			(pinfunction "VSS_ANA")
			(pintype "passive")
		)
		(pad "J6" smd circle
			(at -2.6 -1.3 180)
			(size 0.254 0.254)
			(layers "F.Cu" "F.Mask" "F.Paste")
			(net 229 "Net-(U4D-RSENSE)")
			(pinfunction "RSENSE")
			(pintype "passive")
		)
		(pad "J8" smd circle
			(at -1.95 -1.3 180)
			(size 0.254 0.254)
			(layers "F.Cu" "F.Mask" "F.Paste")
			(net 23 "GND")
			(pinfunction "VSS")
			(pintype "passive")
		)
		(pad "J9" smd circle
			(at -1.3 -1.3 180)
			(size 0.254 0.254)
			(layers "F.Cu" "F.Mask" "F.Paste")
			(net 68 "/TB Controller - Power/VCC_0P9")
			(pinfunction "VCC0P9_SVR_SENSE")
			(pintype "power_in")
		)
		(pad "J11" smd circle
			(at -0.65 -1.3 180)
			(size 0.254 0.254)
			(layers "F.Cu" "F.Mask" "F.Paste")
			(net 180 "Net-(U4A-VCC0P9_LVR_SENSE)")
			(pinfunction "VCC0P9_LVR")
			(pintype "passive")
		)
		(pad "J12" smd circle
			(at 0 -1.3 180)
			(size 0.254 0.254)
			(layers "F.Cu" "F.Mask" "F.Paste")
			(net 23 "GND")
			(pinfunction "VSS")
			(pintype "passive")
		)
		(pad "J13" smd circle
			(at 0.65 -1.3 180)
			(size 0.254 0.254)
			(layers "F.Cu" "F.Mask" "F.Paste")
			(net 23 "GND")
			(pinfunction "VSS")
			(pintype "passive")
		)
		(pad "J15" smd circle
			(at 1.3 -1.3 180)
			(size 0.254 0.254)
			(layers "F.Cu" "F.Mask" "F.Paste")
			(net 23 "GND")
			(pinfunction "VSS")
			(pintype "passive")
		)
		(pad "J16" smd circle
			(at 1.95 -1.3 180)
			(size 0.254 0.254)
			(layers "F.Cu" "F.Mask" "F.Paste")
			(net 178 "Net-(U4A-VCC3P3_ANA_USB2)")
			(pinfunction "VCC3P3_ANA_USB2")
			(pintype "power_in")
		)
		(pad "J18" smd circle
			(at 2.6 -1.3 180)
			(size 0.254 0.254)
			(layers "F.Cu" "F.Mask" "F.Paste")
			(net 23 "GND")
			(pinfunction "VSS_ANA")
			(pintype "passive")
		)
		(pad "J19" smd circle
			(at 3.25 -1.3 180)
			(size 0.254 0.254)
			(layers "F.Cu" "F.Mask" "F.Paste")
			(net 23 "GND")
			(pinfunction "VSS_ANA")
			(pintype "passive")
		)
		(pad "J20" smd circle
			(at 3.9 -1.3 180)
			(size 0.254 0.254)
			(layers "F.Cu" "F.Mask" "F.Paste")
			(net 23 "GND")
			(pinfunction "VSS_ANA")
			(pintype "passive")
		)
		(pad "J22" smd circle
			(at 4.6 -1.38 180)
			(size 0.254 0.254)
			(layers "F.Cu" "F.Mask" "F.Paste")
			(net 23 "GND")
			(pinfunction "VSS_ANA")
			(pintype "passive")
		)
		(pad "J23" smd oval
			(at 5.06 -1.38 270)
			(size 0.1578 0.3302)
			(layers "F.Cu" "F.Mask" "F.Paste")
			(net 23 "GND")
			(pinfunction "VSS_ANA")
			(pintype "passive")
		)
		(pad "K1" smd oval
			(at -5.06 -0.92 270)
			(size 0.1578 0.3302)
			(layers "F.Cu" "F.Mask" "F.Paste")
			(net 23 "GND")
			(pinfunction "VSS_ANA")
			(pintype "passive")
		)
		(pad "K2" smd circle
			(at -4.6 -0.92 180)
			(size 0.254 0.254)
			(layers "F.Cu" "F.Mask" "F.Paste")
			(net 23 "GND")
			(pinfunction "VSS_ANA")
			(pintype "passive")
		)
		(pad "K22" smd circle
			(at 4.6 -0.92 180)
			(size 0.254 0.254)
			(layers "F.Cu" "F.Mask" "F.Paste")
			(net 318 "/TB Controller/TB_PCIE_TX2_N")
			(pinfunction "PCIE_TX2_N")
			(pintype "input")
		)
		(pad "K23" smd oval
			(at 5.06 -0.92 270)
			(size 0.1578 0.3302)
			(layers "F.Cu" "F.Mask" "F.Paste")
			(net 327 "/TB Controller/TB_PCIE_TX2_P")
			(pinfunction "PCIE_TX2_P")
			(pintype "input")
		)
		(pad "L1" smd oval
			(at -5.06 -0.46 270)
			(size 0.1578 0.3302)
			(layers "F.Cu" "F.Mask" "F.Paste")
			(net 275 "unconnected-(U4C-DPSRC_ML2_N-PadL1)")
			(pinfunction "DPSRC_ML2_N")
			(pintype "output+no_connect")
		)
		(pad "L2" smd circle
			(at -4.6 -0.46 180)
			(size 0.254 0.254)
			(layers "F.Cu" "F.Mask" "F.Paste")
			(net 276 "unconnected-(U4C-DPSRC_ML2_P-PadL2)")
			(pinfunction "DPSRC_ML2_P")
			(pintype "output+no_connect")
		)
		(pad "L4" smd circle
			(at -3.9 -0.65 180)
			(size 0.254 0.254)
			(layers "F.Cu" "F.Mask" "F.Paste")
			(net 392 "/TB Controller/~{PE_RST}")
			(pinfunction "PERST_N")
			(pintype "input")
		)
		(pad "L5" smd circle
			(at -3.25 -0.65 180)
			(size 0.254 0.254)
			(layers "F.Cu" "F.Mask" "F.Paste")
			(net 23 "GND")
			(pinfunction "VSS_ANA")
			(pintype "passive")
		)
		(pad "L6" smd circle
			(at -2.6 -0.65 180)
			(size 0.254 0.254)
			(layers "F.Cu" "F.Mask" "F.Paste")
			(net 402 "Net-(C52-Pad2)")
			(pinfunction "VCC0P9_ANA_DPSRC")
			(pintype "power_in")
		)
		(pad "L8" smd circle
			(at -1.95 -0.65 180)
			(size 0.254 0.254)
			(layers "F.Cu" "F.Mask" "F.Paste")
			(net 402 "Net-(C52-Pad2)")
			(pinfunction "VCC0P9_DP")
			(pintype "passive")
		)
		(pad "L9" smd circle
			(at -1.3 -0.65 180)
			(size 0.254 0.254)
			(layers "F.Cu" "F.Mask" "F.Paste")
			(net 68 "/TB Controller - Power/VCC_0P9")
			(pinfunction "VCC0P9_SVR")
			(pintype "power_in")
		)
		(pad "L11" smd circle
			(at -0.65 -0.65 180)
			(size 0.254 0.254)
			(layers "F.Cu" "F.Mask" "F.Paste")
			(net 402 "Net-(C52-Pad2)")
			(pinfunction "VCC0P9_DP")
			(pintype "power_in")
		)
		(pad "L12" smd circle
			(at 0 -0.65 180)
			(size 0.254 0.254)
			(layers "F.Cu" "F.Mask" "F.Paste")
			(net 402 "Net-(C52-Pad2)")
			(pinfunction "VCC0P9_DP")
			(pintype "passive")
		)
		(pad "L13" smd circle
			(at 0.65 -0.65 180)
			(size 0.254 0.254)
			(layers "F.Cu" "F.Mask" "F.Paste")
			(net 23 "GND")
			(pinfunction "VSS")
			(pintype "passive")
		)
		(pad "L15" smd circle
			(at 1.3 -0.65 180)
			(size 0.254 0.254)
			(layers "F.Cu" "F.Mask" "F.Paste")
			(net 23 "GND")
			(pinfunction "FUSE_VQPS_64")
			(pintype "passive")
		)
		(pad "L16" smd circle
			(at 1.95 -0.65 180)
			(size 0.254 0.254)
			(layers "F.Cu" "F.Mask" "F.Paste")
			(net 177 "Net-(U4A-VCC3P3_ANA_PCIE)")
			(pinfunction "VCC3P3_ANA_PCIE")
			(pintype "power_in")
		)
		(pad "L18" smd circle
			(at 2.6 -0.65 180)
			(size 0.254 0.254)
			(layers "F.Cu" "F.Mask" "F.Paste")
			(net 403 "Net-(C55-Pad2)")
			(pinfunction "VCC0P9_ANA_PCIE_2")
			(pintype "power_in")
		)
		(pad "L19" smd circle
			(at 3.25 -0.65 180)
			(size 0.254 0.254)
			(layers "F.Cu" "F.Mask" "F.Paste")
			(net 403 "Net-(C55-Pad2)")
			(pinfunction "VCC0P9_ANA_PCIE_1")
			(pintype "power_in")
		)
		(pad "L20" smd circle
			(at 3.9 -0.65 180)
			(size 0.254 0.254)
			(layers "F.Cu" "F.Mask" "F.Paste")
			(net 23 "GND")
			(pinfunction "VSS_ANA")
			(pintype "passive")
		)
		(pad "L22" smd circle
			(at 4.6 -0.46 180)
			(size 0.254 0.254)
			(layers "F.Cu" "F.Mask" "F.Paste")
			(net 23 "GND")
			(pinfunction "VSS_ANA")
			(pintype "passive")
		)
		(pad "L23" smd oval
			(at 5.06 -0.46 270)
			(size 0.1578 0.3302)
			(layers "F.Cu" "F.Mask" "F.Paste")
			(net 23 "GND")
			(pinfunction "VSS_ANA")
			(pintype "passive")
		)
		(pad "M1" smd oval
			(at -5.06 0 270)
			(size 0.1578 0.3302)
			(layers "F.Cu" "F.Mask" "F.Paste")
			(net 23 "GND")
			(pinfunction "VSS_ANA")
			(pintype "passive")
		)
		(pad "M2" smd circle
			(at -4.6 0 180)
			(size 0.254 0.254)
			(layers "F.Cu" "F.Mask" "F.Paste")
			(net 23 "GND")
			(pinfunction "VSS_ANA")
			(pintype "passive")
		)
		(pad "M4" smd circle
			(at -3.9 0 180)
			(size 0.254 0.254)
			(layers "F.Cu" "F.Mask" "F.Paste")
			(net 374 "/PD and TB DC-DC/HPD")
			(pinfunction "PA_DPSRC_HPD")
			(pintype "input")
		)
		(pad "M5" smd circle
			(at -3.25 0 180)
			(size 0.254 0.254)
			(layers "F.Cu" "F.Mask" "F.Paste")
			(net 23 "GND")
			(pinfunction "VSS_ANA")
			(pintype "passive")
		)
		(pad "M6" smd circle
			(at -2.6 0 180)
			(size 0.254 0.254)
			(layers "F.Cu" "F.Mask" "F.Paste")
			(net 402 "Net-(C52-Pad2)")
			(pinfunction "VCC0P9_ANA_DPSRC")
			(pintype "passive")
		)
		(pad "M8" smd circle
			(at -1.95 0 180)
			(size 0.254 0.254)
			(layers "F.Cu" "F.Mask" "F.Paste")
			(net 402 "Net-(C52-Pad2)")
			(pinfunction "VCC0P9_DP")
			(pintype "passive")
		)
		(pad "M9" smd circle
			(at -1.3 0 180)
			(size 0.254 0.254)
			(layers "F.Cu" "F.Mask" "F.Paste")
			(net 68 "/TB Controller - Power/VCC_0P9")
			(pinfunction "VCC0P9_SVR")
			(pintype "passive")
		)
		(pad "M11" smd circle
			(at -0.65 0 180)
			(size 0.254 0.254)
			(layers "F.Cu" "F.Mask" "F.Paste")
			(net 23 "GND")
			(pinfunction "VSS")
			(pintype "passive")
		)
		(pad "M12" smd circle
			(at 0 0 180)
			(size 0.254 0.254)
			(layers "F.Cu" "F.Mask" "F.Paste")
			(net 23 "GND")
			(pinfunction "VSS")
			(pintype "passive")
		)
		(pad "M13" smd circle
			(at 0.65 0 180)
			(size 0.254 0.254)
			(layers "F.Cu" "F.Mask" "F.Paste")
			(net 403 "Net-(C55-Pad2)")
			(pinfunction "VCC0P9_PCIE")
			(pintype "power_in")
		)
		(pad "M15" smd circle
			(at 1.3 0 180)
			(size 0.254 0.254)
			(layers "F.Cu" "F.Mask" "F.Paste")
			(net 403 "Net-(C55-Pad2)")
			(pinfunction "VCC0P9_PCIE")
			(pintype "passive")
		)
		(pad "M16" smd circle
			(at 1.95 0 180)
			(size 0.254 0.254)
			(layers "F.Cu" "F.Mask" "F.Paste")
			(net 403 "Net-(C55-Pad2)")
			(pinfunction "VCC0P9_PCIE")
			(pintype "passive")
		)
		(pad "M18" smd circle
			(at 2.6 0 180)
			(size 0.254 0.254)
			(layers "F.Cu" "F.Mask" "F.Paste")
			(net 403 "Net-(C55-Pad2)")
			(pinfunction "VCC0P9_ANA_PCIE_2")
			(pintype "passive")
		)
		(pad "M19" smd circle
			(at 3.25 0 180)
			(size 0.254 0.254)
			(layers "F.Cu" "F.Mask" "F.Paste")
			(net 23 "GND")
			(pinfunction "VSS_ANA")
			(pintype "passive")
		)
		(pad "M20" smd circle
			(at 3.9 0 180)
			(size 0.254 0.254)
			(layers "F.Cu" "F.Mask" "F.Paste")
			(net 23 "GND")
			(pinfunction "VSS_ANA")
			(pintype "passive")
		)
		(pad "M22" smd circle
			(at 4.6 0 180)
			(size 0.254 0.254)
			(layers "F.Cu" "F.Mask" "F.Paste")
			(net 598 "/TB Controller/PCIex4.TX2-")
			(pinfunction "PCIE_RX2_N")
			(pintype "input")
		)
		(pad "M23" smd oval
			(at 5.06 0 270)
			(size 0.1578 0.3302)
			(layers "F.Cu" "F.Mask" "F.Paste")
			(net 602 "/TB Controller/PCIex4.TX2+")
			(pinfunction "PCIE_RX2_P")
			(pintype "input")
		)
		(pad "N1" smd oval
			(at -5.06 0.46 270)
			(size 0.1578 0.3302)
			(layers "F.Cu" "F.Mask" "F.Paste")
			(net 277 "unconnected-(U4C-DPSRC_ML1_N-PadN1)")
			(pinfunction "DPSRC_ML1_N")
			(pintype "output+no_connect")
		)
		(pad "N2" smd circle
			(at -4.6 0.46 180)
			(size 0.254 0.254)
			(layers "F.Cu" "F.Mask" "F.Paste")
			(net 278 "unconnected-(U4C-DPSRC_ML1_P-PadN2)")
			(pinfunction "DPSRC_ML1_P")
			(pintype "output+no_connect")
		)
		(pad "N4" smd circle
			(at -3.9 0.65 180)
			(size 0.254 0.254)
			(layers "F.Cu" "F.Mask" "F.Paste")
			(net 222 "Net-(U4C-DPSNK1_DDC_DATA)")
			(pinfunction "DPSNK1_DDC_DATA")
			(pintype "passive")
		)
		(pad "N5" smd circle
			(at -3.25 0.65 180)
			(size 0.254 0.254)
			(layers "F.Cu" "F.Mask" "F.Paste")
			(net 23 "GND")
			(pinfunction "VSS_ANA")
			(pintype "passive")
		)
		(pad "N6" smd circle
			(at -2.6 0.65 180)
			(size 0.254 0.254)
			(layers "F.Cu" "F.Mask" "F.Paste")
			(net 185 "Net-(U4C-DPSRC_RBIAS)")
			(pinfunction "DPSRC_RBIAS")
			(pintype "passive")
		)
		(pad "N8" smd circle
			(at -1.95 0.65 180)
			(size 0.254 0.254)
			(layers "F.Cu" "F.Mask" "F.Paste")
			(net 23 "GND")
			(pinfunction "VSS")
			(pintype "passive")
		)
		(pad "N9" smd circle
			(at -1.3 0.65 180)
			(size 0.254 0.254)
			(layers "F.Cu" "F.Mask" "F.Paste")
			(net 23 "GND")
			(pinfunction "VSS")
			(pintype "passive")
		)
		(pad "N11" smd circle
			(at -0.65 0.65 180)
			(size 0.254 0.254)
			(layers "F.Cu" "F.Mask" "F.Paste")
			(net 23 "GND")
			(pinfunction "VSS")
			(pintype "passive")
		)
		(pad "N12" smd circle
			(at 0 0.65 180)
			(size 0.254 0.254)
			(layers "F.Cu" "F.Mask" "F.Paste")
			(net 23 "GND")
			(pinfunction "VSS")
			(pintype "passive")
		)
		(pad "N13" smd circle
			(at 0.65 0.65 180)
			(size 0.254 0.254)
			(layers "F.Cu" "F.Mask" "F.Paste")
			(net 23 "GND")
			(pinfunction "VSS")
			(pintype "passive")
		)
		(pad "N15" smd circle
			(at 1.3 0.65 180)
			(size 0.254 0.254)
			(layers "F.Cu" "F.Mask" "F.Paste")
			(net 23 "GND")
			(pinfunction "FUSE_VQPS_128")
			(pintype "passive")
		)
		(pad "N16" smd circle
			(at 1.95 0.65 180)
			(size 0.254 0.254)
			(layers "F.Cu" "F.Mask" "F.Paste")
			(net 183 "Net-(U4B-PCIE_RBIAS)")
			(pinfunction "PCIE_RBIAS")
			(pintype "input")
		)
		(pad "N18" smd circle
			(at 2.6 0.65 180)
			(size 0.254 0.254)
			(layers "F.Cu" "F.Mask" "F.Paste")
			(net 403 "Net-(C55-Pad2)")
			(pinfunction "VCC0P9_ANA_PCIE_2")
			(pintype "passive")
		)
		(pad "N19" smd circle
			(at 3.25 0.65 180)
			(size 0.254 0.254)
			(layers "F.Cu" "F.Mask" "F.Paste")
			(net 403 "Net-(C55-Pad2)")
			(pinfunction "VCC0P9_ANA_PCIE_1")
			(pintype "passive")
		)
		(pad "N20" smd circle
			(at 3.9 0.65 180)
			(size 0.254 0.254)
			(layers "F.Cu" "F.Mask" "F.Paste")
			(net 23 "GND")
			(pinfunction "VSS_ANA")
			(pintype "passive")
		)
		(pad "N22" smd circle
			(at 4.6 0.46 180)
			(size 0.254 0.254)
			(layers "F.Cu" "F.Mask" "F.Paste")
			(net 23 "GND")
			(pinfunction "VSS_ANA")
			(pintype "passive")
		)
		(pad "N23" smd oval
			(at 5.06 0.46 270)
			(size 0.1578 0.3302)
			(layers "F.Cu" "F.Mask" "F.Paste")
			(net 23 "GND")
			(pinfunction "VSS_ANA")
			(pintype "passive")
		)
		(pad "P1" smd oval
			(at -5.06 0.92 270)
			(size 0.1578 0.3302)
			(layers "F.Cu" "F.Mask" "F.Paste")
			(net 23 "GND")
			(pinfunction "VSS_ANA")
			(pintype "passive")
		)
	)
)
